(kicad_pcb
	(version 20260206)
	(generator "pcbnew")
	(generator_version "10.0")
	(general
		(thickness 1.6)
		(legacy_teardrops no)
	)
	(paper "A4")
	(title_block
		(title "Bryce Canyon_IOM_IOC_16318-2_OCP.brd")
		(comment 1 "Bryce Canyon / footprints 722-730 of 1605")
	)
	(layers
		(0 "F.Cu" signal "TOP")
		(4 "In1.Cu" signal "L2GND")
		(6 "In2.Cu" signal "L3")
		(8 "In3.Cu" signal "L4VCC")
		(10 "In4.Cu" signal "L5VCC")
		(12 "In5.Cu" signal "L6")
		(14 "In6.Cu" signal "L7GND")
		(2 "B.Cu" signal "BOTTOM")
		(9 "F.Adhes" user "F.Adhesive")
		(11 "B.Adhes" user "B.Adhesive")
		(13 "F.Paste" user "Package Geometry/Pastemask Top")
		(15 "B.Paste" user "Package Geometry/Pastemask Bottom")
		(5 "F.SilkS" user "Ref Des/Silkscreen Top")
		(7 "B.SilkS" user "Ref Des/Silkscreen Bottom")
		(1 "F.Mask" user "Board Geometry/Soldermask Top")
		(3 "B.Mask" user "Board Geometry/Soldermask Bottom")
		(17 "Dwgs.User" user "User.Drawings")
		(19 "Cmts.User" user "User.Comments")
		(21 "Eco1.User" user "User.Eco1")
		(23 "Eco2.User" user "User.Eco2")
		(25 "Edge.Cuts" user "Board Geometry/Outline")
		(27 "Margin" user)
		(31 "F.CrtYd" user "Package Geometry/Place Bound Top")
		(29 "B.CrtYd" user "Package Geometry/Place Bound Bottom")
		(35 "F.Fab" user "Ref Des/Assembly Top")
		(33 "B.Fab" user "Ref Des/Assembly Bottom")
	)
	(footprint ""
		(layer "F.Cu")
		(at 93.642688 -62.302136 90)
		(property "Reference" "R501"
			(at 0 0 90)
			(layer "F.SilkS")
			(hide yes)
			(effects
				(font
					(size 1.27 1.27)
				)
			)
		)
		(property "Value" "2K2R2J-2-GP"
			(at 0.064008 -3.993896 90)
			(unlocked yes)
			(layer "F.Fab")
			(hide yes)
			(effects
				(font
					(size 1.016 1.016)
					(thickness 0.1524)
				)
			)
		)
		(property "Device Type" "R402H16"
			(at 0.064008 -5.517896 90)
			(unlocked yes)
			(layer "F.Fab")
			(hide yes)
			(effects
				(font
					(size 1.016 1.016)
					(thickness 0.1524)
				)
			)
		)
		(duplicate_pad_numbers_are_jumpers no)
		(fp_line
			(start 0.508 -0.9398)
			(end -0.508 -0.9398)
			(stroke
				(width 0.1524)
				(type default)
			)
			(layer "F.SilkS")
		)
		(fp_line
			(start -0.508 -0.9398)
			(end -0.508 0.9398)
			(stroke
				(width 0.1524)
				(type default)
			)
			(layer "F.SilkS")
		)
		(fp_rect
			(start -0.508 0.9398)
			(end 0.508 -0.9398)
			(stroke
				(width 0)
				(type default)
			)
			(fill no)
			(layer "F.CrtYd")
		)
		(fp_rect
			(start -0.508 0.9398)
			(end 0.508 -0.9398)
			(stroke
				(width 0)
				(type default)
			)
			(fill no)
			(layer "F.Fab")
		)
		(pad "1" smd custom
			(at 0 -0.4445 90)
			(size 0.1397 0.1397)
			(layers "F.Cu" "F.Mask" "F.Paste")
			(net "P3V3_STBY")
			(options
				(clearance outline)
				(anchor circle)
			)
			(primitives
				(gr_poly
					(pts
						(arc
							(start -0.1778 -0.2794)
							(mid -0.249642 -0.249642)
							(end -0.2794 -0.1778)
						)
						(arc
							(start -0.2794 0.1778)
							(mid -0.249642 0.249642)
							(end -0.1778 0.2794)
						)
						(arc
							(start 0.1778 0.2794)
							(mid 0.249642 0.249642)
							(end 0.2794 0.1778)
						)
						(arc
							(start 0.2794 -0.1778)
							(mid 0.249642 -0.249642)
							(end 0.1778 -0.2794)
						)
					)
					(width 0)
					(fill yes)
				)
			)
		)
		(pad "2" smd custom
			(at 0 0.4445 90)
			(size 0.1397 0.1397)
			(layers "F.Cu" "F.Mask" "F.Paste")
			(net "IOM_FULL_PWR_EN")
			(options
				(clearance outline)
				(anchor circle)
			)
			(primitives
				(gr_poly
					(pts
						(arc
							(start -0.1778 -0.2794)
							(mid -0.249642 -0.249642)
							(end -0.2794 -0.1778)
						)
						(arc
							(start -0.2794 0.1778)
							(mid -0.249642 0.249642)
							(end -0.1778 0.2794)
						)
						(arc
							(start 0.1778 0.2794)
							(mid 0.249642 0.249642)
							(end 0.2794 0.1778)
						)
						(arc
							(start 0.2794 -0.1778)
							(mid 0.249642 -0.249642)
							(end 0.1778 -0.2794)
						)
					)
					(width 0)
					(fill yes)
				)
			)
		)
	)
	(footprint ""
		(layer "F.Cu")
		(at 75.311 -148.336 180)
		(property "Reference" "C76"
			(at 0 0 180)
			(layer "F.SilkS")
			(hide yes)
			(effects
				(font
					(size 1.27 1.27)
				)
			)
		)
		(property "Value" "SCD01U25V2KX-3GP"
			(at 1.1811 -2.7051 180)
			(unlocked yes)
			(layer "F.Fab")
			(hide yes)
			(effects
				(font
					(size 1.016 1.016)
					(thickness 0.1524)
				)
			)
		)
		(property "Device Type" "C402H22"
			(at 1.1811 -4.2291 180)
			(unlocked yes)
			(layer "F.Fab")
			(hide yes)
			(effects
				(font
					(size 1.016 1.016)
					(thickness 0.1524)
				)
			)
		)
		(duplicate_pad_numbers_are_jumpers no)
		(fp_rect
			(start -0.4318 0.9525)
			(end 0.4318 -0.9525)
			(stroke
				(width 0)
				(type default)
			)
			(fill no)
			(layer "F.CrtYd")
		)
		(fp_rect
			(start -0.4318 0.9525)
			(end 0.4318 -0.9525)
			(stroke
				(width 0)
				(type default)
			)
			(fill no)
			(layer "F.Fab")
		)
		(pad "1" smd custom
			(at 0 -0.4445 180)
			(size 0.1524 0.1524)
			(layers "F.Cu" "F.Mask" "F.Paste")
			(net "P3V3_STBY")
			(options
				(clearance outline)
				(anchor circle)
			)
			(primitives
				(gr_poly
					(pts
						(arc
							(start 0.3048 -0.2032)
							(mid 0.275042 -0.275042)
							(end 0.2032 -0.3048)
						)
						(arc
							(start -0.2032 -0.3048)
							(mid -0.275042 -0.275042)
							(end -0.3048 -0.2032)
						)
						(arc
							(start -0.3048 0.2032)
							(mid -0.275042 0.275042)
							(end -0.2032 0.3048)
						)
						(arc
							(start 0.2032 0.3048)
							(mid 0.275042 0.275042)
							(end 0.3048 0.2032)
						)
					)
					(width 0)
					(fill yes)
				)
			)
		)
		(pad "2" smd custom
			(at 0 0.4445 180)
			(size 0.1524 0.1524)
			(layers "F.Cu" "F.Mask" "F.Paste")
			(net "GND")
			(options
				(clearance outline)
				(anchor circle)
			)
			(primitives
				(gr_poly
					(pts
						(arc
							(start 0.3048 -0.2032)
							(mid 0.275042 -0.275042)
							(end 0.2032 -0.3048)
						)
						(arc
							(start -0.2032 -0.3048)
							(mid -0.275042 -0.275042)
							(end -0.3048 -0.2032)
						)
						(arc
							(start -0.3048 0.2032)
							(mid -0.275042 0.275042)
							(end -0.2032 0.3048)
						)
						(arc
							(start 0.2032 0.3048)
							(mid 0.275042 0.275042)
							(end 0.3048 0.2032)
						)
					)
					(width 0)
					(fill yes)
				)
			)
		)
	)
	(footprint ""
		(layer "F.Cu")
		(at 169.037 -178.8668 -90)
		(property "Reference" "C164"
			(at 0 0 270)
			(layer "F.SilkS")
			(hide yes)
			(effects
				(font
					(size 1.27 1.27)
				)
			)
		)
		(property "Value" "SC10U16V5KX-7-GP-U"
			(at -0.0762 -6.1214 270)
			(unlocked yes)
			(layer "F.Fab")
			(hide yes)
			(effects
				(font
					(size 1.016 1.016)
					(thickness 0.1524)
				)
			)
		)
		(property "Device Type" "C805H58"
			(at -0.0762 -8.1534 270)
			(unlocked yes)
			(layer "F.Fab")
			(hide yes)
			(effects
				(font
					(size 1.016 1.016)
					(thickness 0.1524)
				)
			)
		)
		(duplicate_pad_numbers_are_jumpers no)
		(fp_line
			(start 0.635 0)
			(end -0.635 0)
			(stroke
				(width 0.508)
				(type default)
			)
			(layer "F.SilkS")
		)
		(fp_rect
			(start -0.9652 1.778)
			(end 0.9652 -1.778)
			(stroke
				(width 0)
				(type default)
			)
			(fill no)
			(layer "F.CrtYd")
		)
		(fp_poly
			(pts
				(xy -0.9652 -1.778) (xy 0.9652 -1.778) (xy 0.9652 1.778) (xy -0.9652 1.778)
			)
			(stroke
				(width 0)
				(type default)
			)
			(fill no)
			(layer "F.Fab")
		)
		(pad "1" smd rect
			(at 0 -0.9652 270)
			(size 1.397 1.143)
			(layers "F.Cu" "F.Mask" "F.Paste")
			(net "P5V_STBY")
		)
		(pad "2" smd rect
			(at 0 0.9652 270)
			(size 1.397 1.143)
			(layers "F.Cu" "F.Mask" "F.Paste")
			(net "GND")
		)
	)
	(footprint ""
		(layer "F.Cu")
		(at 17.99971 -24.99995)
		(property "Reference" ""
			(at 0 0 0)
			(layer "F.SilkS")
			(hide yes)
			(effects
				(font
					(size 1.27 1.27)
				)
			)
		)
		(property "Value" "*"
			(at -6.38175 0.19685 0)
			(unlocked yes)
			(layer "F.Fab")
			(hide yes)
			(effects
				(font
					(size 1.016 1.016)
					(thickness 0.1524)
				)
			)
		)
		(duplicate_pad_numbers_are_jumpers no)
		(fp_poly
			(pts
				(arc
					(start 5.0673 0)
					(mid -5.0673 0)
					(end 5.0673 0)
				)
			)
			(stroke
				(width 0)
				(type default)
			)
			(fill no)
			(layer "B.CrtYd")
		)
		(fp_poly
			(pts
				(arc
					(start 5.0673 0)
					(mid -5.0673 0)
					(end 5.0673 0)
				)
			)
			(stroke
				(width 0)
				(type default)
			)
			(fill no)
			(layer "F.CrtYd")
		)
		(fp_poly
			(pts
				(arc
					(start 5.0673 0)
					(mid -5.0673 0)
					(end 5.0673 0)
				)
			)
			(stroke
				(width 0)
				(type default)
			)
			(fill no)
			(layer "B.Fab")
		)
		(fp_poly
			(pts
				(arc
					(start 5.0673 0)
					(mid -5.0673 0)
					(end 5.0673 0)
				)
			)
			(stroke
				(width 0)
				(type default)
			)
			(fill no)
			(layer "F.Fab")
		)
		(pad "1" thru_hole circle
			(at 0 0)
			(size 9.525 9.525)
			(drill 3.5052)
			(layers "*.Cu" "*.Mask")
			(remove_unused_layers no)
			(net "Net_6")
			(clearance -2.5019)
			(thermal_gap 0.3048)
			(padstack
				(mode front_inner_back)
				(layer "Inner"
					(shape circle)
					(size 3.9116 3.9116)
					(clearance 0.3048)
				)
				(layer "B.Cu"
					(shape circle)
					(size 9.525 9.525)
					(clearance -2.5019)
				)
			)
		)
	)
	(footprint ""
		(layer "F.Cu")
		(at 111.0742 -10.834878 -90)
		(property "Reference" "C148"
			(at 0 0 270)
			(layer "F.SilkS")
			(hide yes)
			(effects
				(font
					(size 1.27 1.27)
				)
			)
		)
		(property "Value" "SCD1U50V3KX-GP"
			(at 0 -2.8194 270)
			(unlocked yes)
			(layer "F.Fab")
			(hide yes)
			(effects
				(font
					(size 1.016 1.016)
					(thickness 0.1524)
				)
			)
		)
		(property "Device Type" "C603H36"
			(at 0 -4.3434 270)
			(unlocked yes)
			(layer "F.Fab")
			(hide yes)
			(effects
				(font
					(size 1.016 1.016)
					(thickness 0.1524)
				)
			)
		)
		(duplicate_pad_numbers_are_jumpers no)
		(fp_line
			(start 0.508 0)
			(end -0.508 0)
			(stroke
				(width 0.2032)
				(type default)
			)
			(layer "F.SilkS")
		)
		(fp_rect
			(start -0.5842 1.3335)
			(end 0.5842 -1.3335)
			(stroke
				(width 0)
				(type default)
			)
			(fill no)
			(layer "F.CrtYd")
		)
		(fp_rect
			(start -0.5842 1.3335)
			(end 0.5842 -1.3335)
			(stroke
				(width 0)
				(type default)
			)
			(fill no)
			(layer "F.Fab")
		)
		(pad "1" smd custom
			(at 0 -0.762 270)
			(size 0.2159 0.2159)
			(layers "F.Cu" "F.Mask" "F.Paste")
			(net "MB0_ISET_R")
			(options
				(clearance outline)
				(anchor circle)
			)
			(primitives
				(gr_poly
					(pts
						(arc
							(start -0.3302 -0.4318)
							(mid -0.402042 -0.402042)
							(end -0.4318 -0.3302)
						)
						(arc
							(start -0.4318 0.3302)
							(mid -0.402042 0.402042)
							(end -0.3302 0.4318)
						)
						(arc
							(start 0.3302 0.4318)
							(mid 0.402042 0.402042)
							(end 0.4318 0.3302)
						)
						(arc
							(start 0.4318 -0.3302)
							(mid 0.402042 -0.402042)
							(end 0.3302 -0.4318)
						)
					)
					(width 0)
					(fill yes)
				)
			)
		)
		(pad "2" smd custom
			(at 0 0.762 270)
			(size 0.2159 0.2159)
			(layers "F.Cu" "F.Mask" "F.Paste")
			(net "AGND_CURRENT_MON")
			(options
				(clearance outline)
				(anchor circle)
			)
			(primitives
				(gr_poly
					(pts
						(arc
							(start -0.3302 -0.4318)
							(mid -0.402042 -0.402042)
							(end -0.4318 -0.3302)
						)
						(arc
							(start -0.4318 0.3302)
							(mid -0.402042 0.402042)
							(end -0.3302 0.4318)
						)
						(arc
							(start 0.3302 0.4318)
							(mid 0.402042 0.402042)
							(end 0.4318 0.3302)
						)
						(arc
							(start 0.4318 -0.3302)
							(mid 0.402042 -0.402042)
							(end 0.3302 -0.4318)
						)
					)
					(width 0)
					(fill yes)
				)
			)
		)
	)
	(footprint ""
		(layer "F.Cu")
		(at 95.070168 -148.6154)
		(property "Reference" "R41"
			(at 0 0 0)
			(layer "F.SilkS")
			(hide yes)
			(effects
				(font
					(size 1.27 1.27)
				)
			)
		)
		(property "Value" "4K7R2F-GP"
			(at 0.064008 -3.993896 0)
			(unlocked yes)
			(layer "F.Fab")
			(hide yes)
			(effects
				(font
					(size 1.016 1.016)
					(thickness 0.1524)
				)
			)
		)
		(property "Device Type" "R402H16"
			(at 0.064008 -5.517896 0)
			(unlocked yes)
			(layer "F.Fab")
			(hide yes)
			(effects
				(font
					(size 1.016 1.016)
					(thickness 0.1524)
				)
			)
		)
		(duplicate_pad_numbers_are_jumpers no)
		(fp_line
			(start -0.508 -0.9398)
			(end -0.508 0.9398)
			(stroke
				(width 0.1524)
				(type default)
			)
			(layer "F.SilkS")
		)
		(fp_line
			(start 0.508 -0.9398)
			(end -0.508 -0.9398)
			(stroke
				(width 0.1524)
				(type default)
			)
			(layer "F.SilkS")
		)
		(fp_rect
			(start -0.508 0.9398)
			(end 0.508 -0.9398)
			(stroke
				(width 0)
				(type default)
			)
			(fill no)
			(layer "F.CrtYd")
		)
		(fp_rect
			(start -0.508 0.9398)
			(end 0.508 -0.9398)
			(stroke
				(width 0)
				(type default)
			)
			(fill no)
			(layer "F.Fab")
		)
		(pad "1" smd custom
			(at 0 -0.4445)
			(size 0.1397 0.1397)
			(layers "F.Cu" "F.Mask" "F.Paste")
			(net "USB_EN_2")
			(options
				(clearance outline)
				(anchor circle)
			)
			(primitives
				(gr_poly
					(pts
						(arc
							(start -0.1778 -0.2794)
							(mid -0.249642 -0.249642)
							(end -0.2794 -0.1778)
						)
						(arc
							(start -0.2794 0.1778)
							(mid -0.249642 0.249642)
							(end -0.1778 0.2794)
						)
						(arc
							(start 0.1778 0.2794)
							(mid 0.249642 0.249642)
							(end 0.2794 0.1778)
						)
						(arc
							(start 0.2794 -0.1778)
							(mid 0.249642 -0.249642)
							(end 0.1778 -0.2794)
						)
					)
					(width 0)
					(fill yes)
				)
			)
		)
		(pad "2" smd custom
			(at 0 0.4445)
			(size 0.1397 0.1397)
			(layers "F.Cu" "F.Mask" "F.Paste")
			(net "GND")
			(options
				(clearance outline)
				(anchor circle)
			)
			(primitives
				(gr_poly
					(pts
						(arc
							(start -0.1778 -0.2794)
							(mid -0.249642 -0.249642)
							(end -0.2794 -0.1778)
						)
						(arc
							(start -0.2794 0.1778)
							(mid -0.249642 0.249642)
							(end -0.1778 0.2794)
						)
						(arc
							(start 0.1778 0.2794)
							(mid 0.249642 0.249642)
							(end 0.2794 0.1778)
						)
						(arc
							(start 0.2794 -0.1778)
							(mid 0.249642 -0.249642)
							(end 0.1778 -0.2794)
						)
					)
					(width 0)
					(fill yes)
				)
			)
		)
	)
	(footprint ""
		(layer "F.Cu")
		(at 164.203126 -106.473244)
		(property "Reference" "R623"
			(at 0 0 0)
			(layer "F.SilkS")
			(hide yes)
			(effects
				(font
					(size 1.27 1.27)
				)
			)
		)
		(property "Value" "150R2F-1-GP"
			(at 0.064008 -3.993896 0)
			(unlocked yes)
			(layer "F.Fab")
			(hide yes)
			(effects
				(font
					(size 1.016 1.016)
					(thickness 0.1524)
				)
			)
		)
		(property "Device Type" "R402H16"
			(at 0.064008 -5.517896 0)
			(unlocked yes)
			(layer "F.Fab")
			(hide yes)
			(effects
				(font
					(size 1.016 1.016)
					(thickness 0.1524)
				)
			)
		)
		(duplicate_pad_numbers_are_jumpers no)
		(fp_line
			(start -0.508 -0.9398)
			(end -0.508 0.9398)
			(stroke
				(width 0.1524)
				(type default)
			)
			(layer "F.SilkS")
		)
		(fp_line
			(start 0.508 -0.9398)
			(end -0.508 -0.9398)
			(stroke
				(width 0.1524)
				(type default)
			)
			(layer "F.SilkS")
		)
		(fp_rect
			(start -0.508 0.9398)
			(end 0.508 -0.9398)
			(stroke
				(width 0)
				(type default)
			)
			(fill no)
			(layer "F.CrtYd")
		)
		(fp_rect
			(start -0.508 0.9398)
			(end 0.508 -0.9398)
			(stroke
				(width 0)
				(type default)
			)
			(fill no)
			(layer "F.Fab")
		)
		(pad "1" smd custom
			(at 0 -0.4445)
			(size 0.1397 0.1397)
			(layers "F.Cu" "F.Mask" "F.Paste")
			(net "P3V3")
			(options
				(clearance outline)
				(anchor circle)
			)
			(primitives
				(gr_poly
					(pts
						(arc
							(start -0.1778 -0.2794)
							(mid -0.249642 -0.249642)
							(end -0.2794 -0.1778)
						)
						(arc
							(start -0.2794 0.1778)
							(mid -0.249642 0.249642)
							(end -0.1778 0.2794)
						)
						(arc
							(start 0.1778 0.2794)
							(mid 0.249642 0.249642)
							(end 0.2794 0.1778)
						)
						(arc
							(start 0.2794 -0.1778)
							(mid 0.249642 -0.249642)
							(end 0.1778 -0.2794)
						)
					)
					(width 0)
					(fill yes)
				)
			)
		)
		(pad "2" smd custom
			(at 0 0.4445)
			(size 0.1397 0.1397)
			(layers "F.Cu" "F.Mask" "F.Paste")
			(net "SYS_HB_LED_R")
			(options
				(clearance outline)
				(anchor circle)
			)
			(primitives
				(gr_poly
					(pts
						(arc
							(start -0.1778 -0.2794)
							(mid -0.249642 -0.249642)
							(end -0.2794 -0.1778)
						)
						(arc
							(start -0.2794 0.1778)
							(mid -0.249642 0.249642)
							(end -0.1778 0.2794)
						)
						(arc
							(start 0.1778 0.2794)
							(mid 0.249642 0.249642)
							(end 0.2794 0.1778)
						)
						(arc
							(start 0.2794 -0.1778)
							(mid 0.249642 -0.249642)
							(end 0.1778 -0.2794)
						)
					)
					(width 0)
					(fill yes)
				)
			)
		)
	)
	(footprint ""
		(layer "F.Cu")
		(at 153.7716 -38.4556)
		(property "Reference" "TP182"
			(at 0 0 0)
			(layer "F.SilkS")
			(hide yes)
			(effects
				(font
					(size 1.27 1.27)
				)
			)
		)
		(property "Value" "TPAD28-2-GP"
			(at -0.0127 -1.6637 0)
			(unlocked yes)
			(layer "F.Fab")
			(hide yes)
			(effects
				(font
					(size 1.016 1.016)
					(thickness 0.1524)
				)
			)
		)
		(property "Device Type" "TPAD28"
			(at -0.0127 -3.1877 0)
			(unlocked yes)
			(layer "F.Fab")
			(hide yes)
			(effects
				(font
					(size 1.016 1.016)
					(thickness 0.1524)
				)
			)
		)
		(duplicate_pad_numbers_are_jumpers no)
		(fp_poly
			(pts
				(arc
					(start 0.3556 0)
					(mid -0.3556 0)
					(end 0.3556 0)
				)
			)
			(stroke
				(width 0)
				(type default)
			)
			(fill no)
			(layer "F.CrtYd")
		)
		(fp_poly
			(pts
				(arc
					(start 0.6096 0)
					(mid -0.6096 0)
					(end 0.6096 0)
				)
			)
			(stroke
				(width 0)
				(type default)
			)
			(fill no)
			(layer "F.Fab")
		)
		(pad "1" smd circle
			(at 0 0)
			(size 0.7112 0.7112)
			(layers "F.Cu" "F.Mask" "F.Paste")
			(net "ZDEF_EXTB_TP_B1")
		)
	)
	(footprint ""
		(layer "F.Cu")
		(at 224.249234 -60.455048 180)
		(property "Reference" "C305"
			(at 0 0 180)
			(layer "F.SilkS")
			(hide yes)
			(effects
				(font
					(size 1.27 1.27)
				)
			)
		)
		(property "Value" "SC12P50V2JN-3GP"
			(at 1.1811 -2.7051 180)
			(unlocked yes)
			(layer "F.Fab")
			(hide yes)
			(effects
				(font
					(size 1.016 1.016)
					(thickness 0.1524)
				)
			)
		)
		(property "Device Type" "C402H24"
			(at 1.1811 -4.2291 180)
			(unlocked yes)
			(layer "F.Fab")
			(hide yes)
			(effects
				(font
					(size 1.016 1.016)
					(thickness 0.1524)
				)
			)
		)
		(duplicate_pad_numbers_are_jumpers no)
		(fp_rect
			(start -0.4318 0.9525)
			(end 0.4318 -0.9525)
			(stroke
				(width 0)
				(type default)
			)
			(fill no)
			(layer "F.CrtYd")
		)
		(fp_rect
			(start -0.4318 0.9525)
			(end 0.4318 -0.9525)
			(stroke
				(width 0)
				(type default)
			)
			(fill no)
			(layer "F.Fab")
		)
		(pad "1" smd custom
			(at 0 -0.4445 180)
			(size 0.1524 0.1524)
			(layers "F.Cu" "F.Mask" "F.Paste")
			(net "IOC_REF_CLK_P")
			(options
				(clearance outline)
				(anchor circle)
			)
			(primitives
				(gr_poly
					(pts
						(arc
							(start 0.3048 -0.2032)
							(mid 0.275042 -0.275042)
							(end 0.2032 -0.3048)
						)
						(arc
							(start -0.2032 -0.3048)
							(mid -0.275042 -0.275042)
							(end -0.3048 -0.2032)
						)
						(arc
							(start -0.3048 0.2032)
							(mid -0.275042 0.275042)
							(end -0.2032 0.3048)
						)
						(arc
							(start 0.2032 0.3048)
							(mid 0.275042 0.275042)
							(end 0.3048 0.2032)
						)
					)
					(width 0)
					(fill yes)
				)
			)
		)
		(pad "2" smd custom
			(at 0 0.4445 180)
			(size 0.1524 0.1524)
			(layers "F.Cu" "F.Mask" "F.Paste")
			(net "GND")
			(options
				(clearance outline)
				(anchor circle)
			)
			(primitives
				(gr_poly
					(pts
						(arc
							(start 0.3048 -0.2032)
							(mid 0.275042 -0.275042)
							(end 0.2032 -0.3048)
						)
						(arc
							(start -0.2032 -0.3048)
							(mid -0.275042 -0.275042)
							(end -0.3048 -0.2032)
						)
						(arc
							(start -0.3048 0.2032)
							(mid -0.275042 0.275042)
							(end -0.2032 0.3048)
						)
						(arc
							(start 0.2032 0.3048)
							(mid 0.275042 0.275042)
							(end 0.3048 0.2032)
						)
					)
					(width 0)
					(fill yes)
				)
			)
		)
	)
)
